#ISCELL
  pure_quanta quanta_title_block_c *
  *
#CELL
  pure_quanta pt5161lrs *
  page427_i1
#ISCELL
  standard tap *
  page427_i10
#ISCELL
  standard tap *
  page427_i11
#ISCELL
  standard tap *
  page427_i12
#ISCELL
  standard tap *
  page427_i13
#ISCELL
  standard tap *
  page427_i14
#ISCELL
  standard tap *
  page427_i15
#ISCELL
  standard tap *
  page427_i16
#ISCELL
  standard tap *
  page427_i17
#ISCELL
  standard offpage *
  page427_i18
#ISCELL
  standard offpage *
  page427_i19
#ISCELL
  standard tap *
  page427_i2
#ISCELL
  standard tap *
  page427_i20
#ISCELL
  standard tap *
  page427_i21
#ISCELL
  standard tap *
  page427_i22
#ISCELL
  standard tap *
  page427_i23
#ISCELL
  standard tap *
  page427_i24
#ISCELL
  standard tap *
  page427_i25
#ISCELL
  standard tap *
  page427_i26
#ISCELL
  standard tap *
  page427_i27
#ISCELL
  standard tap *
  page427_i28
#ISCELL
  standard tap *
  page427_i29
#ISCELL
  standard tap *
  page427_i3
#ISCELL
  standard tap *
  page427_i30
#ISCELL
  standard tap *
  page427_i31
#ISCELL
  standard tap *
  page427_i32
#ISCELL
  standard tap *
  page427_i33
#ISCELL
  standard tap *
  page427_i34
#ISCELL
  standard tap *
  page427_i35
#ISCELL
  standard offpage *
  page427_i36
#ISCELL
  standard offpage *
  page427_i37
#CELL
  pure_quanta pt5161lrs *
  page427_i38
#ISCELL
  standard tap *
  page427_i4
#ISCELL
  standard tap *
  page427_i5
#ISCELL
  standard tap *
  page427_i6
#ISCELL
  standard tap *
  page427_i7
#ISCELL
  standard tap *
  page427_i8
#ISCELL
  standard tap *
  page427_i9
